(kicad_pcb
	(version 20211014)
	(generator pcbnew)
	(general
    (thickness 1.6)
  )
	(paper "A4")
	(title_block
    (title "SA800U (Snapdragon 845) Baseboard")
    (date "2023-10-19")
    (rev "1.0.3")
    (company "Antmicro Ltd.")
    (comment 1 "www.antmicro.com")
		(comment 9 "footprints 184-192 of 589")
	)
	(layers
    (0 "F.Cu" signal)
    (1 "In1.Cu" power)
    (2 "In2.Cu" signal)
    (3 "In3.Cu" signal)
    (4 "In4.Cu" power)
    (31 "B.Cu" signal)
    (32 "B.Adhes" user "B.Adhesive")
    (33 "F.Adhes" user "F.Adhesive")
    (34 "B.Paste" user)
    (35 "F.Paste" user)
    (36 "B.SilkS" user "B.Silkscreen")
    (37 "F.SilkS" user "F.Silkscreen")
    (38 "B.Mask" user)
    (39 "F.Mask" user)
    (40 "Dwgs.User" user "User.Drawings")
    (41 "Cmts.User" user "User.Comments")
    (42 "Eco1.User" user "User.Eco1")
    (43 "Eco2.User" user "User.Eco2")
    (44 "Edge.Cuts" user)
    (45 "Margin" user)
    (46 "B.CrtYd" user "B.Courtyard")
    (47 "F.CrtYd" user "F.Courtyard")
    (48 "B.Fab" user)
    (49 "F.Fab" user)
  )
	(footprint "sa800u-baseboard-hw-footprints:UQFN-12_2x1.7mm_P0.4mm_Texas_RUT" (layer "F.Cu")
    (tedit 5F354333)
    (at 133.888164 127.312953)
    (descr "Texas_R_PUQFN-N12")
    (tags "Texas_R_PUQFN-N12")
    (property "Author" "Antmicro")
    (property "License" "Apache-2.0")
    (property "MPN" "TXB0104RUTR")
    (property "Manufacturer" "Texas Instruments")
    (property "Sheetfile" "hdmi-converter.kicad_sch")
    (property "Sheetname" "HDMI converter")
    (attr smd)
    (fp_text reference "U2" (at 1.931836 0.767047 90) (layer "F.SilkS")
      (effects (font (size 0.7 0.7) (thickness 0.15)) (justify left bottom))
    )
    (fp_text value "TXB0104_UQFN" (at 0 2.35) (layer "F.Fab")
      (effects (font (size 0.7 0.7) (thickness 0.15)) (justify left bottom))
    )
    (fp_text user "License: Apache-2.0" (at -1.1 6.75) (layer "F.Fab") hide
      (effects (font (size 0.7 0.7) (thickness 0.15)) (justify left bottom))
    )
    (fp_text user "${REFERENCE}" (at -1.1 5.55) (layer "F.Fab") hide
      (effects (font (size 0.7 0.7) (thickness 0.15)) (justify left bottom))
    )
    (fp_text user "Author: Antmicro" (at -1.1 4.35) (layer "F.Fab") hide
      (effects (font (size 0.7 0.7) (thickness 0.15)) (justify left bottom))
    )
    (fp_line (start 0.497 1.3) (end -0.5 1.3) (layer "F.SilkS") (width 0.15))
    (fp_line (start 0.597 -1.301) (end -0.55 -1.301) (layer "F.SilkS") (width 0.15))
    (fp_circle (center -0.85 -1.2) (end -0.8 -1.2) (layer "F.SilkS") (width 0.15) (fill solid))
    (fp_rect (start -1.1 -1.3) (end 1.1 1.3) (layer "F.CrtYd") (width 0.05) (fill none))
    (fp_line (start 0.847 -1) (end 0.847 0.997) (layer "F.Fab") (width 0.15))
    (fp_line (start -0.5 -1) (end 0.847 -1) (layer "F.Fab") (width 0.15))
    (fp_line (start -0.85 0.997) (end -0.85 -0.5) (layer "F.Fab") (width 0.15))
    (fp_line (start -0.5 -1) (end -0.85 -0.5) (layer "F.Fab") (width 0.15))
    (fp_line (start 0.847 0.997) (end -0.85 0.997) (layer "F.Fab") (width 0.15))
    (pad "1" smd rect (at -0.425 -0.975) (size 0.15 0.25) (layers "F.Cu" "F.Paste" "F.Mask")
      (net 132 "VREG_S4A_1V8") (pinfunction "VCCA") (pintype "power_in"))
    (pad "1" smd rect (at -0.653 -0.803 270) (size 0.2 0.6) (layers "F.Cu" "F.Paste" "F.Mask")
      (net 132 "VREG_S4A_1V8") (pinfunction "VCCA") (pintype "power_in"))
    (pad "2" smd rect (at -0.653 -0.403 270) (size 0.2 0.6) (layers "F.Cu" "F.Paste" "F.Mask")
      (net 59 "I2S1_WS") (pinfunction "A1") (pintype "tri_state"))
    (pad "3" smd rect (at -0.653 0 270) (size 0.2 0.6) (layers "F.Cu" "F.Paste" "F.Mask")
      (net 61 "I2S1_SCK") (pinfunction "A2") (pintype "tri_state"))
    (pad "4" smd rect (at -0.653 0.4 270) (size 0.2 0.6) (layers "F.Cu" "F.Paste" "F.Mask")
      (net 60 "I2S1_MCLK") (pinfunction "A3") (pintype "tri_state"))
    (pad "5" smd rect (at -0.653 0.8 270) (size 0.2 0.6) (layers "F.Cu" "F.Paste" "F.Mask")
      (net 62 "I2S1_DATA0") (pinfunction "A4") (pintype "tri_state"))
    (pad "6" smd rect (at 0 0.8 270) (size 0.6 0.2) (layers "F.Cu" "F.Paste" "F.Mask")
      (net 1 "GND") (pinfunction "GND") (pintype "power_in"))
    (pad "7" smd rect (at 0.65 0.8 270) (size 0.2 0.6) (layers "F.Cu" "F.Paste" "F.Mask")
      (net 297 "/HDMI converter/LT9611_I2S_D0_SPDIF") (pinfunction "B4") (pintype "tri_state"))
    (pad "8" smd rect (at 0.65 0.4 270) (size 0.2 0.6) (layers "F.Cu" "F.Paste" "F.Mask")
      (net 300 "/HDMI converter/LT9611_I2S_MCLK") (pinfunction "B3") (pintype "tri_state"))
    (pad "9" smd rect (at 0.65 0 270) (size 0.2 0.6) (layers "F.Cu" "F.Paste" "F.Mask")
      (net 299 "/HDMI converter/LT9611_I2S_SCLK") (pinfunction "B2") (pintype "tri_state"))
    (pad "10" smd rect (at 0.65 -0.403 270) (size 0.2 0.6) (layers "F.Cu" "F.Paste" "F.Mask")
      (net 298 "/HDMI converter/LT9611_I2S_WS") (pinfunction "B1") (pintype "tri_state"))
    (pad "11" smd rect (at 0.65 -0.803 270) (size 0.2 0.6) (layers "F.Cu" "F.Paste" "F.Mask")
      (net 131 "3V3_SYS") (pinfunction "VCCB") (pintype "power_in"))
    (pad "12" smd rect (at 0 -0.803 270) (size 0.6 0.2) (layers "F.Cu" "F.Paste" "F.Mask")
      (net 132 "VREG_S4A_1V8") (pinfunction "OE") (pintype "input"))
  )
	(footprint "sa800u-baseboard-hw-footprints:C_0402_1005Metric" (layer "F.Cu")
    (tedit 616D63CF)
    (at 148.8 125.75)
    (descr "Capacitor SMD 0402")
    (tags "capacitor SMD 0402")
    (property "Author" "Antmicro")
    (property "Dielectric" "")
    (property "License" "Apache-2.0")
    (property "MPN" "MC0402N150J500CT")
    (property "Manufacturer" "Multicomp")
    (property "Sheetfile" "hdmi-converter.kicad_sch")
    (property "Sheetname" "HDMI converter")
    (property "Val" "15p")
    (property "Voltage" "")
    (attr smd)
    (fp_text reference "C19" (at -1.01 -0.59) (layer "F.SilkS")
      (effects (font (size 0.7 0.7) (thickness 0.15)) (justify left bottom))
    )
    (fp_text value "C_15p_0402" (at 0 1.4) (layer "F.Fab")
      (effects (font (size 0.7 0.7) (thickness 0.15)) (justify left bottom))
    )
    (fp_text user "License: Apache-2.0" (at -0.932 5.17) (layer "F.Fab") hide
      (effects (font (size 0.7 0.7) (thickness 0.15)) (justify left bottom))
    )
    (fp_text user "${REFERENCE}" (at -0.932 3.168) (layer "F.Fab") hide
      (effects (font (size 0.7 0.7) (thickness 0.15)) (justify left bottom))
    )
    (fp_text user "Author: Antmicro" (at -0.932 4.17) (layer "F.Fab") hide
      (effects (font (size 0.7 0.7) (thickness 0.15)) (justify left bottom))
    )
    (fp_rect (start -0.94 -0.47) (end 0.94 0.47) (layer "F.CrtYd") (width 0.05) (fill none))
    (fp_rect (start -0.499 -0.249) (end 0.499 0.249) (layer "F.Fab") (width 0.15) (fill none))
    (pad "1" smd roundrect (at -0.484 0) (size 0.59 0.64) (layers "F.Cu" "F.Paste" "F.Mask") (roundrect_rratio 0.25)
      (net 190 "/HDMI converter/XTALO") (pintype "passive"))
    (pad "2" smd roundrect (at 0.484 0) (size 0.59 0.64) (layers "F.Cu" "F.Paste" "F.Mask") (roundrect_rratio 0.25)
      (net 1 "GND") (pintype "passive"))
  )
	(footprint "sa800u-baseboard-hw-footprints:R_0402_1005Metric" (layer "F.Cu")
    (tedit 5FD9C158)
    (at 138.35 136.9 -90)
    (descr "Resistor SMD 0402")
    (tags "resistor SMD 0402")
    (property "Author" "Antmicro")
    (property "License" "Apache-2.0")
    (property "MPN" "CR0402-FX-5100GLF")
    (property "Manufacturer" "Bourns")
    (property "Sheetfile" "hdmi-converter.kicad_sch")
    (property "Sheetname" "HDMI converter")
    (property "Tolerance" "1%")
    (property "Val" "510R")
    (attr smd)
    (fp_text reference "R49" (at -4.62 15.6 -90) (layer "F.SilkS")
      (effects (font (size 0.7 0.7) (thickness 0.15)) (justify left bottom))
    )
    (fp_text value "R_510R_0402" (at 0 1.4 -90) (layer "F.Fab")
      (effects (font (size 0.7 0.7) (thickness 0.15)) (justify left bottom))
    )
    (fp_text user "Author: Antmicro" (at -0.95 4.169 -90) (layer "F.Fab") hide
      (effects (font (size 0.7 0.7) (thickness 0.15)) (justify left bottom))
    )
    (fp_text user "${REFERENCE}" (at -0.95 3.168 -90) (layer "F.Fab") hide
      (effects (font (size 0.7 0.7) (thickness 0.15)) (justify left bottom))
    )
    (fp_text user "License: Apache-2.0" (at -0.95 5.169 -90) (layer "F.Fab") hide
      (effects (font (size 0.7 0.7) (thickness 0.15)) (justify left bottom))
    )
    (fp_rect (start -0.93 -0.47) (end 0.93 0.47) (layer "F.CrtYd") (width 0.05) (fill none))
    (fp_rect (start -0.5 -0.25) (end 0.5 0.25) (layer "F.Fab") (width 0.15) (fill none))
    (pad "1" smd roundrect (at -0.485 0 270) (size 0.59 0.64) (layers "F.Cu" "F.Paste" "F.Mask") (roundrect_rratio 0.25)
      (net 206 "/HDMI converter/HDMI_CLK_P") (pintype "passive"))
    (pad "2" smd roundrect (at 0.485 0 270) (size 0.59 0.64) (layers "F.Cu" "F.Paste" "F.Mask") (roundrect_rratio 0.25)
      (net 209 "/HDMI converter/VCOM") (pintype "passive"))
  )
	(footprint "sa800u-baseboard-hw-footprints:C_0402_1005Metric" (layer "F.Cu")
    (tedit 616D63CF)
    (at 133.7 130.05 180)
    (descr "Capacitor SMD 0402")
    (tags "capacitor SMD 0402")
    (property "Author" "Antmicro")
    (property "Dielectric" "")
    (property "License" "Apache-2.0")
    (property "MPN" "C1005X6S1A105K050BC")
    (property "Manufacturer" "TDK")
    (property "Sheetfile" "hdmi-converter.kicad_sch")
    (property "Sheetname" "HDMI converter")
    (property "Val" "1u")
    (property "Voltage" "")
    (attr smd)
    (fp_text reference "C26" (at -0.92 -0.43 180) (layer "F.SilkS")
      (effects (font (size 0.7 0.7) (thickness 0.15)) (justify left bottom))
    )
    (fp_text value "C_1u_0402" (at 0 1.4 180) (layer "F.Fab")
      (effects (font (size 0.7 0.7) (thickness 0.15)) (justify left bottom))
    )
    (fp_text user "${REFERENCE}" (at -0.932 3.168 180) (layer "F.Fab") hide
      (effects (font (size 0.7 0.7) (thickness 0.15)) (justify left bottom))
    )
    (fp_text user "License: Apache-2.0" (at -0.932 5.17 180) (layer "F.Fab") hide
      (effects (font (size 0.7 0.7) (thickness 0.15)) (justify left bottom))
    )
    (fp_text user "Author: Antmicro" (at -0.932 4.17 180) (layer "F.Fab") hide
      (effects (font (size 0.7 0.7) (thickness 0.15)) (justify left bottom))
    )
    (fp_rect (start -0.94 -0.47) (end 0.94 0.47) (layer "F.CrtYd") (width 0.05) (fill none))
    (fp_rect (start -0.499 -0.249) (end 0.499 0.249) (layer "F.Fab") (width 0.15) (fill none))
    (pad "1" smd roundrect (at -0.484 0 180) (size 0.59 0.64) (layers "F.Cu" "F.Paste" "F.Mask") (roundrect_rratio 0.25)
      (net 184 "/HDMI converter/LT9611_VCC33_IO") (pintype "passive"))
    (pad "2" smd roundrect (at 0.484 0 180) (size 0.59 0.64) (layers "F.Cu" "F.Paste" "F.Mask") (roundrect_rratio 0.25)
      (net 1 "GND") (pintype "passive"))
  )
	(footprint "sa800u-baseboard-hw-footprints:C_0402_1005Metric" (layer "F.Cu")
    (tedit 616D63CF)
    (at 137.75 134.95 -90)
    (descr "Capacitor SMD 0402")
    (tags "capacitor SMD 0402")
    (property "Author" "Antmicro")
    (property "Dielectric" "X5R")
    (property "License" "Apache-2.0")
    (property "MPN" "GRM155R61H104KE14D")
    (property "Manufacturer" "Murata")
    (property "Sheetfile" "hdmi-converter.kicad_sch")
    (property "Sheetname" "HDMI converter")
    (property "Val" "100n")
    (property "Voltage" "50V")
    (attr smd)
    (fp_text reference "C53" (at -4.61 15.55 -90) (layer "F.SilkS")
      (effects (font (size 0.7 0.7) (thickness 0.15)) (justify left bottom))
    )
    (fp_text value "C_100n_0402" (at 0 1.4 -90) (layer "F.Fab")
      (effects (font (size 0.7 0.7) (thickness 0.15)) (justify left bottom))
    )
    (fp_text user "License: Apache-2.0" (at -0.932 5.17 -90) (layer "F.Fab") hide
      (effects (font (size 0.7 0.7) (thickness 0.15)) (justify left bottom))
    )
    (fp_text user "${REFERENCE}" (at -0.932 3.168 -90) (layer "F.Fab") hide
      (effects (font (size 0.7 0.7) (thickness 0.15)) (justify left bottom))
    )
    (fp_text user "Author: Antmicro" (at -0.932 4.17 -90) (layer "F.Fab") hide
      (effects (font (size 0.7 0.7) (thickness 0.15)) (justify left bottom))
    )
    (fp_rect (start -0.94 -0.47) (end 0.94 0.47) (layer "F.CrtYd") (width 0.05) (fill none))
    (fp_rect (start -0.499 -0.249) (end 0.499 0.249) (layer "F.Fab") (width 0.15) (fill none))
    (pad "1" smd roundrect (at -0.484 0 270) (size 0.59 0.64) (layers "F.Cu" "F.Paste" "F.Mask") (roundrect_rratio 0.25)
      (net 205 "/HDMI converter/HDMI_TX_CLK_P") (pintype "passive"))
    (pad "2" smd roundrect (at 0.484 0 270) (size 0.59 0.64) (layers "F.Cu" "F.Paste" "F.Mask") (roundrect_rratio 0.25)
      (net 206 "/HDMI converter/HDMI_CLK_P") (pintype "passive"))
  )
	(footprint "sa800u-baseboard-hw-footprints:C_0402_1005Metric" (layer "F.Cu")
    (tedit 616D63CF)
    (at 140.95 134.95 -90)
    (descr "Capacitor SMD 0402")
    (tags "capacitor SMD 0402")
    (property "Author" "Antmicro")
    (property "Dielectric" "X5R")
    (property "License" "Apache-2.0")
    (property "MPN" "GRM155R61H104KE14D")
    (property "Manufacturer" "Murata")
    (property "Sheetfile" "hdmi-converter.kicad_sch")
    (property "Sheetname" "HDMI converter")
    (property "Val" "100n")
    (property "Voltage" "50V")
    (attr smd)
    (fp_text reference "C52" (at -4.579 15.87 -90) (layer "F.SilkS")
      (effects (font (size 0.7 0.7) (thickness 0.15)) (justify left bottom))
    )
    (fp_text value "C_100n_0402" (at 0 1.4 -90) (layer "F.Fab")
      (effects (font (size 0.7 0.7) (thickness 0.15)) (justify left bottom))
    )
    (fp_text user "${REFERENCE}" (at -0.932 3.168 -90) (layer "F.Fab") hide
      (effects (font (size 0.7 0.7) (thickness 0.15)) (justify left bottom))
    )
    (fp_text user "License: Apache-2.0" (at -0.932 5.17 -90) (layer "F.Fab") hide
      (effects (font (size 0.7 0.7) (thickness 0.15)) (justify left bottom))
    )
    (fp_text user "Author: Antmicro" (at -0.932 4.17 -90) (layer "F.Fab") hide
      (effects (font (size 0.7 0.7) (thickness 0.15)) (justify left bottom))
    )
    (fp_rect (start -0.94 -0.47) (end 0.94 0.47) (layer "F.CrtYd") (width 0.05) (fill none))
    (fp_rect (start -0.499 -0.249) (end 0.499 0.249) (layer "F.Fab") (width 0.15) (fill none))
    (pad "1" smd roundrect (at -0.484 0 270) (size 0.59 0.64) (layers "F.Cu" "F.Paste" "F.Mask") (roundrect_rratio 0.25)
      (net 202 "/HDMI converter/HDMI_TX_D0_P") (pintype "passive"))
    (pad "2" smd roundrect (at 0.484 0 270) (size 0.59 0.64) (layers "F.Cu" "F.Paste" "F.Mask") (roundrect_rratio 0.25)
      (net 201 "/HDMI converter/HDMI_TX0_P") (pintype "passive"))
  )
	(footprint "sa800u-baseboard-hw-footprints:R_0402_1005Metric" (layer "F.Cu")
    (tedit 5FD9C158)
    (at 139.35 136.9 -90)
    (descr "Resistor SMD 0402")
    (tags "resistor SMD 0402")
    (property "Author" "Antmicro")
    (property "License" "Apache-2.0")
    (property "MPN" "CR0402-FX-5100GLF")
    (property "Manufacturer" "Bourns")
    (property "Sheetfile" "hdmi-converter.kicad_sch")
    (property "Sheetname" "HDMI converter")
    (property "Tolerance" "1%")
    (property "Val" "510R")
    (attr smd)
    (fp_text reference "R51" (at -4.62 15.68 -90) (layer "F.SilkS")
      (effects (font (size 0.7 0.7) (thickness 0.15)) (justify left bottom))
    )
    (fp_text value "R_510R_0402" (at 0 1.4 -90) (layer "F.Fab")
      (effects (font (size 0.7 0.7) (thickness 0.15)) (justify left bottom))
    )
    (fp_text user "${REFERENCE}" (at -0.95 3.168 -90) (layer "F.Fab") hide
      (effects (font (size 0.7 0.7) (thickness 0.15)) (justify left bottom))
    )
    (fp_text user "Author: Antmicro" (at -0.95 4.169 -90) (layer "F.Fab") hide
      (effects (font (size 0.7 0.7) (thickness 0.15)) (justify left bottom))
    )
    (fp_text user "License: Apache-2.0" (at -0.95 5.169 -90) (layer "F.Fab") hide
      (effects (font (size 0.7 0.7) (thickness 0.15)) (justify left bottom))
    )
    (fp_rect (start -0.93 -0.47) (end 0.93 0.47) (layer "F.CrtYd") (width 0.05) (fill none))
    (fp_rect (start -0.5 -0.25) (end 0.5 0.25) (layer "F.Fab") (width 0.15) (fill none))
    (pad "1" smd roundrect (at -0.485 0 270) (size 0.59 0.64) (layers "F.Cu" "F.Paste" "F.Mask") (roundrect_rratio 0.25)
      (net 203 "/HDMI converter/HDMI_TX0_N") (pintype "passive"))
    (pad "2" smd roundrect (at 0.485 0 270) (size 0.59 0.64) (layers "F.Cu" "F.Paste" "F.Mask") (roundrect_rratio 0.25)
      (net 209 "/HDMI converter/VCOM") (pintype "passive"))
  )
	(footprint "sa800u-baseboard-hw-footprints:R_0402_1005Metric" (layer "F.Cu")
    (tedit 5FD9C158)
    (at 141.55 136.9 -90)
    (descr "Resistor SMD 0402")
    (tags "resistor SMD 0402")
    (property "Author" "Antmicro")
    (property "License" "Apache-2.0")
    (property "MPN" "CR0402-FX-5100GLF")
    (property "Manufacturer" "Bourns")
    (property "Sheetfile" "hdmi-converter.kicad_sch")
    (property "Sheetname" "HDMI converter")
    (property "Tolerance" "1%")
    (property "Val" "510R")
    (attr smd)
    (fp_text reference "R52" (at -4.57 15.91 -90) (layer "F.SilkS")
      (effects (font (size 0.7 0.7) (thickness 0.15)) (justify left bottom))
    )
    (fp_text value "R_510R_0402" (at 0 1.4 -90) (layer "F.Fab")
      (effects (font (size 0.7 0.7) (thickness 0.15)) (justify left bottom))
    )
    (fp_text user "Author: Antmicro" (at -0.95 4.169 -90) (layer "F.Fab") hide
      (effects (font (size 0.7 0.7) (thickness 0.15)) (justify left bottom))
    )
    (fp_text user "${REFERENCE}" (at -0.95 3.168 -90) (layer "F.Fab") hide
      (effects (font (size 0.7 0.7) (thickness 0.15)) (justify left bottom))
    )
    (fp_text user "License: Apache-2.0" (at -0.95 5.169 -90) (layer "F.Fab") hide
      (effects (font (size 0.7 0.7) (thickness 0.15)) (justify left bottom))
    )
    (fp_rect (start -0.93 -0.47) (end 0.93 0.47) (layer "F.CrtYd") (width 0.05) (fill none))
    (fp_rect (start -0.5 -0.25) (end 0.5 0.25) (layer "F.Fab") (width 0.15) (fill none))
    (pad "1" smd roundrect (at -0.485 0 270) (size 0.59 0.64) (layers "F.Cu" "F.Paste" "F.Mask") (roundrect_rratio 0.25)
      (net 201 "/HDMI converter/HDMI_TX0_P") (pintype "passive"))
    (pad "2" smd roundrect (at 0.485 0 270) (size 0.59 0.64) (layers "F.Cu" "F.Paste" "F.Mask") (roundrect_rratio 0.25)
      (net 209 "/HDMI converter/VCOM") (pintype "passive"))
  )
	(footprint "sa800u-baseboard-hw-footprints:R_0402_1005Metric" (layer "F.Cu")
    (tedit 5FD9C158)
    (at 136.3 133.05 -90)
    (descr "Resistor SMD 0402")
    (tags "resistor SMD 0402")
    (property "Author" "Antmicro")
    (property "License" "Apache-2.0")
    (property "MPN" "CR0402-FX-50R0GLF")
    (property "Manufacturer" "Bourns")
    (property "Sheetfile" "hdmi-converter.kicad_sch")
    (property "Sheetname" "HDMI converter")
    (property "Tolerance" "1%")
    (property "Val" "50R")
    (attr smd)
    (fp_text reference "R35" (at -4.611 15.46 -90) (layer "F.SilkS")
      (effects (font (size 0.7 0.7) (thickness 0.15)) (justify left bottom))
    )
    (fp_text value "R_50R_0402" (at 0 1.4 -90) (layer "F.Fab")
      (effects (font (size 0.7 0.7) (thickness 0.15)) (justify left bottom))
    )
    (fp_text user "License: Apache-2.0" (at -0.95 5.169 -90) (layer "F.Fab") hide
      (effects (font (size 0.7 0.7) (thickness 0.15)) (justify left bottom))
    )
    (fp_text user "${REFERENCE}" (at -0.95 3.168 -90) (layer "F.Fab") hide
      (effects (font (size 0.7 0.7) (thickness 0.15)) (justify left bottom))
    )
    (fp_text user "Author: Antmicro" (at -0.95 4.169 -90) (layer "F.Fab") hide
      (effects (font (size 0.7 0.7) (thickness 0.15)) (justify left bottom))
    )
    (fp_rect (start -0.93 -0.47) (end 0.93 0.47) (layer "F.CrtYd") (width 0.05) (fill none))
    (fp_rect (start -0.5 -0.25) (end 0.5 0.25) (layer "F.Fab") (width 0.15) (fill none))
    (pad "1" smd roundrect (at -0.485 0 270) (size 0.59 0.64) (layers "F.Cu" "F.Paste" "F.Mask") (roundrect_rratio 0.25)
      (net 187 "/HDMI converter/LT9611_VCC33_TX") (pintype "passive"))
    (pad "2" smd roundrect (at 0.485 0 270) (size 0.59 0.64) (layers "F.Cu" "F.Paste" "F.Mask") (roundrect_rratio 0.25)
      (net 207 "/HDMI converter/HDMI_TX_CLK_N") (pintype "passive"))
  )
)
